#ISCELL
  pure_quanta quanta_title_block_c *
  *
#ISCELL
  logical_power universal_gnd *
  page42_i1
#CELL
  pure_quanta socket4677_azif0045p001c01cs *
  page42_i10
#CELL
  pure_quanta socket4677_azif0045p001c01cs *
  page42_i11
#CELL
  pure_quanta socket4677_azif0045p001c01cs *
  page42_i12
#ISCELL
  logical_power universal_gnd *
  page42_i3
#ISCELL
  logical_power universal_gnd *
  page42_i4
#ISCELL
  logical_power universal_gnd *
  page42_i6
#ISCELL
  logical_power universal_gnd *
  page42_i7
